(kicad_pcb
	(version 20260206)
	(generator "pcbnew")
	(generator_version "10.0")
	(general
		(thickness 1.6)
		(legacy_teardrops no)
	)
	(paper "A4")
	(title_block
		(title "baseboard — 13948-1b.1110WZS1818.brd")
		(comment 1 "Honey Badger (Wiwynn) / footprints 893-898 of 2523")
	)
	(layers
		(0 "F.Cu" signal "TOP")
		(4 "In1.Cu" signal "L2GND")
		(6 "In2.Cu" signal "L3")
		(8 "In3.Cu" signal "L4VCC")
		(10 "In4.Cu" signal "L5VCC")
		(12 "In5.Cu" signal "L6")
		(14 "In6.Cu" signal "L7GND")
		(2 "B.Cu" signal "BOTTOM")
		(9 "F.Adhes" user "F.Adhesive")
		(11 "B.Adhes" user "B.Adhesive")
		(13 "F.Paste" user "Package Geometry/Pastemask Top")
		(15 "B.Paste" user "Package Geometry/Pastemask Bottom")
		(5 "F.SilkS" user "Ref Des/Silkscreen Top")
		(7 "B.SilkS" user "Ref Des/Silkscreen Bottom")
		(1 "F.Mask" user "Board Geometry/Soldermask Top")
		(3 "B.Mask" user "Board Geometry/Soldermask Bottom")
		(17 "Dwgs.User" user "User.Drawings")
		(19 "Cmts.User" user "User.Comments")
		(21 "Eco1.User" user "User.Eco1")
		(23 "Eco2.User" user "User.Eco2")
		(25 "Edge.Cuts" user "Board Geometry/Outline")
		(27 "Margin" user)
		(31 "F.CrtYd" user "Package Geometry/Place Bound Top")
		(29 "B.CrtYd" user "Package Geometry/Place Bound Bottom")
		(35 "F.Fab" user "Ref Des/Assembly Top")
		(33 "B.Fab" user "Ref Des/Assembly Bottom")
	)
	(footprint ""
		(layer "F.Cu")
		(at 94.869 -4.191)
		(property "Reference" "SC1045"
			(at 0 0 0)
			(layer "F.SilkS")
			(hide yes)
			(effects
				(font
					(size 1.27 1.27)
				)
			)
		)
		(property "Value" "SCD1U16V2KX-3GP"
			(at 1.1811 -2.7051 0)
			(unlocked yes)
			(layer "F.Fab")
			(hide yes)
			(effects
				(font
					(size 1.016 1.016)
					(thickness 0.1524)
				)
			)
		)
		(property "Device Type" "C402H22"
			(at 1.1811 -4.2291 0)
			(unlocked yes)
			(layer "F.Fab")
			(hide yes)
			(effects
				(font
					(size 1.016 1.016)
					(thickness 0.1524)
				)
			)
		)
		(duplicate_pad_numbers_are_jumpers no)
		(fp_rect
			(start -0.4318 0.9525)
			(end 0.4318 -0.9525)
			(stroke
				(width 0)
				(type default)
			)
			(fill no)
			(layer "F.CrtYd")
		)
		(fp_rect
			(start -0.4318 0.9525)
			(end 0.4318 -0.9525)
			(stroke
				(width 0)
				(type default)
			)
			(fill no)
			(layer "F.Fab")
		)
		(pad "1" smd custom
			(at 0 -0.4445)
			(size 0.1524 0.1524)
			(layers "F.Cu" "F.Mask" "F.Paste")
			(net "P0V955_C")
			(options
				(clearance outline)
				(anchor circle)
			)
			(primitives
				(gr_poly
					(pts
						(arc
							(start 0.3048 -0.2032)
							(mid 0.275042 -0.275042)
							(end 0.2032 -0.3048)
						)
						(arc
							(start -0.2032 -0.3048)
							(mid -0.275042 -0.275042)
							(end -0.3048 -0.2032)
						)
						(arc
							(start -0.3048 0.2032)
							(mid -0.275042 0.275042)
							(end -0.2032 0.3048)
						)
						(arc
							(start 0.2032 0.3048)
							(mid 0.275042 0.275042)
							(end 0.3048 0.2032)
						)
					)
					(width 0)
					(fill yes)
				)
			)
		)
		(pad "2" smd custom
			(at 0 0.4445)
			(size 0.1524 0.1524)
			(layers "F.Cu" "F.Mask" "F.Paste")
			(net "GND")
			(options
				(clearance outline)
				(anchor circle)
			)
			(primitives
				(gr_poly
					(pts
						(arc
							(start 0.3048 -0.2032)
							(mid 0.275042 -0.275042)
							(end 0.2032 -0.3048)
						)
						(arc
							(start -0.2032 -0.3048)
							(mid -0.275042 -0.275042)
							(end -0.3048 -0.2032)
						)
						(arc
							(start -0.3048 0.2032)
							(mid -0.275042 0.275042)
							(end -0.2032 0.3048)
						)
						(arc
							(start 0.2032 0.3048)
							(mid 0.275042 0.275042)
							(end 0.3048 0.2032)
						)
					)
					(width 0)
					(fill yes)
				)
			)
		)
	)
	(footprint ""
		(layer "F.Cu")
		(at 341.532718 -150.726648 -90)
		(property "Reference" "U183"
			(at 0 0 270)
			(layer "F.SilkS")
			(hide yes)
			(effects
				(font
					(size 1.27 1.27)
				)
			)
		)
		(property "Value" "USB2514B-AEZC-TR-GP"
			(at -5.5372 -5.2832 270)
			(unlocked yes)
			(layer "F.Fab")
			(hide yes)
			(effects
				(font
					(size 1.016 1.016)
					(thickness 0.1524)
				)
			)
		)
		(property "Device Type" "QFN36-G3D85H40"
			(at -5.5372 -6.8072 270)
			(unlocked yes)
			(layer "F.Fab")
			(hide yes)
			(effects
				(font
					(size 1.016 1.016)
					(thickness 0.1524)
				)
			)
		)
		(duplicate_pad_numbers_are_jumpers no)
		(fp_line
			(start 0.9906 4.318)
			(end 0.9906 3.81)
			(stroke
				(width 0.1524)
				(type default)
			)
			(layer "F.SilkS")
		)
		(fp_line
			(start -4.0132 4.0132)
			(end -4.0132 2.7432)
			(stroke
				(width 0.1524)
				(type default)
			)
			(layer "F.SilkS")
		)
		(fp_line
			(start -2.7432 4.0132)
			(end -4.0132 4.0132)
			(stroke
				(width 0.1524)
				(type default)
			)
			(layer "F.SilkS")
		)
		(fp_line
			(start 2.7432 4.0132)
			(end 4.0132 4.0132)
			(stroke
				(width 0.1524)
				(type default)
			)
			(layer "F.SilkS")
		)
		(fp_line
			(start 4.0132 4.0132)
			(end 4.0132 2.7432)
			(stroke
				(width 0.1524)
				(type default)
			)
			(layer "F.SilkS")
		)
		(fp_line
			(start -1.4986 3.8354)
			(end -1.4986 4.445)
			(stroke
				(width 0.1524)
				(type default)
			)
			(layer "F.SilkS")
		)
		(fp_line
			(start 4.4958 0.9652)
			(end 3.81 0.9652)
			(stroke
				(width 0.1524)
				(type default)
			)
			(layer "F.SilkS")
		)
		(fp_line
			(start -3.8608 0.4826)
			(end -4.318 0.4826)
			(stroke
				(width 0.1524)
				(type default)
			)
			(layer "F.SilkS")
		)
		(fp_line
			(start 4.3434 -1.524)
			(end 3.8608 -1.524)
			(stroke
				(width 0.1524)
				(type default)
			)
			(layer "F.SilkS")
		)
		(fp_line
			(start -3.7846 -2.0066)
			(end -4.4704 -2.0066)
			(stroke
				(width 0.1524)
				(type default)
			)
			(layer "F.SilkS")
		)
		(fp_line
			(start -4.0132 -2.7432)
			(end -4.0132 -4.0132)
			(stroke
				(width 0.1524)
				(type default)
			)
			(layer "F.SilkS")
		)
		(fp_line
			(start -0.0254 -3.7846)
			(end -0.0254 -4.2926)
			(stroke
				(width 0.1524)
				(type default)
			)
			(layer "F.SilkS")
		)
		(fp_line
			(start -4.0132 -4.0132)
			(end -2.7432 -4.0132)
			(stroke
				(width 0.1524)
				(type default)
			)
			(layer "F.SilkS")
		)
		(fp_poly
			(pts
				(xy 2.7432 -4.0132) (xy 4.0132 -2.7432) (xy 4.0132 -4.0132)
			)
			(stroke
				(width 0)
				(type default)
			)
			(fill yes)
			(layer "F.SilkS")
		)
		(fp_rect
			(start -4.0132 4.0132)
			(end 4.0132 -4.0132)
			(stroke
				(width 0)
				(type default)
			)
			(fill no)
			(layer "F.CrtYd")
		)
		(fp_rect
			(start -4.0132 4.0132)
			(end 4.0132 -4.0132)
			(stroke
				(width 0)
				(type default)
			)
			(fill no)
			(layer "F.Fab")
		)
		(pad "1" smd rect
			(at 1.999996 -2.9591 270)
			(size 0.3048 1.0922)
			(layers "F.Cu" "F.Mask" "F.Paste")
			(net "USB_P1_DN")
		)
		(pad "2" smd rect
			(at 1.500124 -2.8702 270)
			(size 0.3048 1.27)
			(layers "F.Cu" "F.Mask" "F.Paste")
			(net "USB_P1_DP")
		)
		(pad "3" smd rect
			(at 0.999998 -2.8702 270)
			(size 0.3048 1.27)
			(layers "F.Cu" "F.Mask" "F.Paste")
			(net "USB_P2_DN")
		)
		(pad "4" smd rect
			(at 0.500126 -2.8702 270)
			(size 0.3048 1.27)
			(layers "F.Cu" "F.Mask" "F.Paste")
			(net "USB_P2_DP")
		)
		(pad "5" smd rect
			(at 0 -2.8702 270)
			(size 0.3048 1.27)
			(layers "F.Cu" "F.Mask" "F.Paste")
			(net "P3V3_STBY")
		)
		(pad "6" smd rect
			(at -0.500126 -2.8702 270)
			(size 0.3048 1.27)
			(layers "F.Cu" "F.Mask" "F.Paste")
			(net "USB_P3_DN")
		)
		(pad "7" smd rect
			(at -0.999998 -2.8702 270)
			(size 0.3048 1.27)
			(layers "F.Cu" "F.Mask" "F.Paste")
			(net "USB_P3_DP")
		)
		(pad "8" smd rect
			(at -1.500124 -2.8702 270)
			(size 0.3048 1.27)
			(layers "F.Cu" "F.Mask" "F.Paste")
			(net "USB_P4_DN")
		)
		(pad "9" smd rect
			(at -1.999996 -2.9591 270)
			(size 0.3048 1.0922)
			(layers "F.Cu" "F.Mask" "F.Paste")
			(net "USB_P4_DP")
		)
		(pad "10" smd rect
			(at -2.9591 -1.999996 270)
			(size 1.0922 0.3048)
			(layers "F.Cu" "F.Mask" "F.Paste")
			(net "P3V3_STBY")
		)
		(pad "11" smd rect
			(at -2.8702 -1.500124 270)
			(size 1.27 0.3048)
			(layers "F.Cu" "F.Mask" "F.Paste")
			(net "GND")
		)
		(pad "12" smd rect
			(at -2.8702 -0.999998 270)
			(size 1.27 0.3048)
			(layers "F.Cu" "F.Mask" "F.Paste")
			(net "USB_EN_1")
		)
		(pad "13" smd rect
			(at -2.8702 -0.500126 270)
			(size 1.27 0.3048)
			(layers "F.Cu" "F.Mask" "F.Paste")
			(net "USB_OCS_N1")
		)
		(pad "14" smd rect
			(at -2.8702 0 270)
			(size 1.27 0.3048)
			(layers "F.Cu" "F.Mask" "F.Paste")
			(net "CRFILT")
		)
		(pad "15" smd rect
			(at -2.8702 0.500126 270)
			(size 1.27 0.3048)
			(layers "F.Cu" "F.Mask" "F.Paste")
			(net "P3V3_STBY")
		)
		(pad "16" smd rect
			(at -2.8702 0.999998 270)
			(size 1.27 0.3048)
			(layers "F.Cu" "F.Mask" "F.Paste")
			(net "USB_EN_2")
		)
		(pad "17" smd rect
			(at -2.8702 1.500124 270)
			(size 1.27 0.3048)
			(layers "F.Cu" "F.Mask" "F.Paste")
			(net "USB_OCS_N2")
		)
		(pad "18" smd rect
			(at -2.9591 1.999996 270)
			(size 1.0922 0.3048)
			(layers "F.Cu" "F.Mask" "F.Paste")
			(net "USB_EN_3")
		)
		(pad "19" smd rect
			(at -1.999996 2.9591 270)
			(size 0.3048 1.0922)
			(layers "F.Cu" "F.Mask" "F.Paste")
			(net "USB_OCS_N3")
		)
		(pad "20" smd rect
			(at -1.500124 2.8702 270)
			(size 0.3048 1.27)
			(layers "F.Cu" "F.Mask" "F.Paste")
			(net "USB_EN_4")
		)
		(pad "21" smd rect
			(at -0.999998 2.8702 270)
			(size 0.3048 1.27)
			(layers "F.Cu" "F.Mask" "F.Paste")
			(net "USB_OCS_N4")
		)
		(pad "22" smd rect
			(at -0.500126 2.8702 270)
			(size 0.3048 1.27)
			(layers "F.Cu" "F.Mask" "F.Paste")
			(net "BMC_I2C_D_SDA")
		)
		(pad "23" smd rect
			(at 0 2.8702 270)
			(size 0.3048 1.27)
			(layers "F.Cu" "F.Mask" "F.Paste")
			(net "P3V3_STBY")
		)
		(pad "24" smd rect
			(at 0.500126 2.8702 270)
			(size 0.3048 1.27)
			(layers "F.Cu" "F.Mask" "F.Paste")
			(net "CFG_SEL0")
		)
		(pad "25" smd rect
			(at 0.999998 2.8702 270)
			(size 0.3048 1.27)
			(layers "F.Cu" "F.Mask" "F.Paste")
			(net "CFG_SEL1")
		)
		(pad "26" smd rect
			(at 1.500124 2.8702 270)
			(size 0.3048 1.27)
			(layers "F.Cu" "F.Mask" "F.Paste")
			(net "USB_RESET_N")
		)
		(pad "27" smd rect
			(at 1.999996 2.9591 270)
			(size 0.3048 1.0922)
			(layers "F.Cu" "F.Mask" "F.Paste")
			(net "VBUS_DET")
		)
		(pad "28" smd rect
			(at 2.9591 1.999996 270)
			(size 1.0922 0.3048)
			(layers "F.Cu" "F.Mask" "F.Paste")
			(net "USB_SUSP_IND")
		)
		(pad "29" smd rect
			(at 2.8702 1.500124 270)
			(size 1.27 0.3048)
			(layers "F.Cu" "F.Mask" "F.Paste")
			(net "P3V3_STBY")
		)
		(pad "30" smd rect
			(at 2.8702 0.999998 270)
			(size 1.27 0.3048)
			(layers "F.Cu" "F.Mask" "F.Paste")
			(net "USB_P0_DN_R")
		)
		(pad "31" smd rect
			(at 2.8702 0.500126 270)
			(size 1.27 0.3048)
			(layers "F.Cu" "F.Mask" "F.Paste")
			(net "USB_P0_DP_R")
		)
		(pad "32" smd rect
			(at 2.8702 0 270)
			(size 1.27 0.3048)
			(layers "F.Cu" "F.Mask" "F.Paste")
			(net "USB_HUB_XTAL_OUT")
		)
		(pad "33" smd rect
			(at 2.8702 -0.500126 270)
			(size 1.27 0.3048)
			(layers "F.Cu" "F.Mask" "F.Paste")
			(net "USB_HUB_XTAL_IN")
		)
		(pad "34" smd rect
			(at 2.8702 -0.999998 270)
			(size 1.27 0.3048)
			(layers "F.Cu" "F.Mask" "F.Paste")
			(net "PLLFILT")
		)
		(pad "35" smd rect
			(at 2.8702 -1.500124 270)
			(size 1.27 0.3048)
			(layers "F.Cu" "F.Mask" "F.Paste")
			(net "RBIAS")
		)
		(pad "36" smd rect
			(at 2.9591 -1.999996 270)
			(size 1.0922 0.3048)
			(layers "F.Cu" "F.Mask" "F.Paste")
			(net "P3V3_STBY")
		)
		(pad "37" smd rect
			(at 0 0 270)
			(size 3.8608 3.8608)
			(layers "F.Cu" "F.Mask" "F.Paste")
			(net "GND")
		)
	)
	(footprint ""
		(layer "F.Cu")
		(at 110.617 -68.199 90)
		(property "Reference" "C328"
			(at 0 0 90)
			(layer "F.SilkS")
			(hide yes)
			(effects
				(font
					(size 1.27 1.27)
				)
			)
		)
		(property "Value" "SCD1U16V2KX-3GP"
			(at 1.1811 -2.7051 90)
			(unlocked yes)
			(layer "F.Fab")
			(hide yes)
			(effects
				(font
					(size 1.016 1.016)
					(thickness 0.1524)
				)
			)
		)
		(property "Device Type" "C402H22"
			(at 1.1811 -4.2291 90)
			(unlocked yes)
			(layer "F.Fab")
			(hide yes)
			(effects
				(font
					(size 1.016 1.016)
					(thickness 0.1524)
				)
			)
		)
		(duplicate_pad_numbers_are_jumpers no)
		(fp_rect
			(start -0.4318 0.9525)
			(end 0.4318 -0.9525)
			(stroke
				(width 0)
				(type default)
			)
			(fill no)
			(layer "F.CrtYd")
		)
		(fp_rect
			(start -0.4318 0.9525)
			(end 0.4318 -0.9525)
			(stroke
				(width 0)
				(type default)
			)
			(fill no)
			(layer "F.Fab")
		)
		(pad "1" smd custom
			(at 0 -0.4445 90)
			(size 0.1524 0.1524)
			(layers "F.Cu" "F.Mask" "F.Paste")
			(net "P3V3_STBY")
			(options
				(clearance outline)
				(anchor circle)
			)
			(primitives
				(gr_poly
					(pts
						(arc
							(start 0.3048 -0.2032)
							(mid 0.275042 -0.275042)
							(end 0.2032 -0.3048)
						)
						(arc
							(start -0.2032 -0.3048)
							(mid -0.275042 -0.275042)
							(end -0.3048 -0.2032)
						)
						(arc
							(start -0.3048 0.2032)
							(mid -0.275042 0.275042)
							(end -0.2032 0.3048)
						)
						(arc
							(start 0.2032 0.3048)
							(mid 0.275042 0.275042)
							(end 0.3048 0.2032)
						)
					)
					(width 0)
					(fill yes)
				)
			)
		)
		(pad "2" smd custom
			(at 0 0.4445 90)
			(size 0.1524 0.1524)
			(layers "F.Cu" "F.Mask" "F.Paste")
			(net "GND")
			(options
				(clearance outline)
				(anchor circle)
			)
			(primitives
				(gr_poly
					(pts
						(arc
							(start 0.3048 -0.2032)
							(mid 0.275042 -0.275042)
							(end 0.2032 -0.3048)
						)
						(arc
							(start -0.2032 -0.3048)
							(mid -0.275042 -0.275042)
							(end -0.3048 -0.2032)
						)
						(arc
							(start -0.3048 0.2032)
							(mid -0.275042 0.275042)
							(end -0.2032 0.3048)
						)
						(arc
							(start 0.2032 0.3048)
							(mid 0.275042 0.275042)
							(end 0.3048 0.2032)
						)
					)
					(width 0)
					(fill yes)
				)
			)
		)
	)
	(footprint ""
		(layer "F.Cu")
		(at 184.712864 -38.172136 180)
		(property "Reference" "R374"
			(at 0 0 180)
			(layer "F.SilkS")
			(hide yes)
			(effects
				(font
					(size 1.27 1.27)
				)
			)
		)
		(property "Value" "2K2R2J-2-GP"
			(at 0.064008 -3.993896 180)
			(unlocked yes)
			(layer "F.Fab")
			(hide yes)
			(effects
				(font
					(size 1.016 1.016)
					(thickness 0.1524)
				)
			)
		)
		(property "Device Type" "R402H16"
			(at 0.064008 -5.517896 180)
			(unlocked yes)
			(layer "F.Fab")
			(hide yes)
			(effects
				(font
					(size 1.016 1.016)
					(thickness 0.1524)
				)
			)
		)
		(duplicate_pad_numbers_are_jumpers no)
		(fp_line
			(start 0.508 -0.9398)
			(end -0.508 -0.9398)
			(stroke
				(width 0.1524)
				(type default)
			)
			(layer "F.SilkS")
		)
		(fp_line
			(start -0.508 -0.9398)
			(end -0.508 0.9398)
			(stroke
				(width 0.1524)
				(type default)
			)
			(layer "F.SilkS")
		)
		(fp_rect
			(start -0.508 0.9398)
			(end 0.508 -0.9398)
			(stroke
				(width 0)
				(type default)
			)
			(fill no)
			(layer "F.CrtYd")
		)
		(fp_rect
			(start -0.508 0.9398)
			(end 0.508 -0.9398)
			(stroke
				(width 0)
				(type default)
			)
			(fill no)
			(layer "F.Fab")
		)
		(pad "1" smd custom
			(at 0 -0.4445 180)
			(size 0.1397 0.1397)
			(layers "F.Cu" "F.Mask" "F.Paste")
			(net "PHY_RESET#")
			(options
				(clearance outline)
				(anchor circle)
			)
			(primitives
				(gr_poly
					(pts
						(arc
							(start -0.1778 -0.2794)
							(mid -0.249642 -0.249642)
							(end -0.2794 -0.1778)
						)
						(arc
							(start -0.2794 0.1778)
							(mid -0.249642 0.249642)
							(end -0.1778 0.2794)
						)
						(arc
							(start 0.1778 0.2794)
							(mid 0.249642 0.249642)
							(end 0.2794 0.1778)
						)
						(arc
							(start 0.2794 -0.1778)
							(mid 0.249642 -0.249642)
							(end 0.1778 -0.2794)
						)
					)
					(width 0)
					(fill yes)
				)
			)
		)
		(pad "2" smd custom
			(at 0 0.4445 180)
			(size 0.1397 0.1397)
			(layers "F.Cu" "F.Mask" "F.Paste")
			(net "GND")
			(options
				(clearance outline)
				(anchor circle)
			)
			(primitives
				(gr_poly
					(pts
						(arc
							(start -0.1778 -0.2794)
							(mid -0.249642 -0.249642)
							(end -0.2794 -0.1778)
						)
						(arc
							(start -0.2794 0.1778)
							(mid -0.249642 0.249642)
							(end -0.1778 0.2794)
						)
						(arc
							(start 0.1778 0.2794)
							(mid 0.249642 0.249642)
							(end 0.2794 0.1778)
						)
						(arc
							(start 0.2794 -0.1778)
							(mid 0.249642 -0.249642)
							(end 0.1778 -0.2794)
						)
					)
					(width 0)
					(fill yes)
				)
			)
		)
	)
	(footprint ""
		(layer "F.Cu")
		(at 78.99019 -59.911488 -90)
		(property "Reference" "SC928"
			(at 0 0 270)
			(layer "F.SilkS")
			(hide yes)
			(effects
				(font
					(size 1.27 1.27)
				)
			)
		)
		(property "Value" "SC10U6D3V5KX-4GP"
			(at -0.0762 -6.1214 270)
			(unlocked yes)
			(layer "F.Fab")
			(hide yes)
			(effects
				(font
					(size 1.016 1.016)
					(thickness 0.1524)
				)
			)
		)
		(property "Device Type" "C805H58"
			(at -0.0762 -8.1534 270)
			(unlocked yes)
			(layer "F.Fab")
			(hide yes)
			(effects
				(font
					(size 1.016 1.016)
					(thickness 0.1524)
				)
			)
		)
		(duplicate_pad_numbers_are_jumpers no)
		(fp_line
			(start 0.635 0)
			(end -0.635 0)
			(stroke
				(width 0.508)
				(type default)
			)
			(layer "F.SilkS")
		)
		(fp_rect
			(start -0.9652 1.778)
			(end 0.9652 -1.778)
			(stroke
				(width 0)
				(type default)
			)
			(fill no)
			(layer "F.CrtYd")
		)
		(fp_poly
			(pts
				(xy -0.9652 -1.778) (xy 0.9652 -1.778) (xy 0.9652 1.778) (xy -0.9652 1.778)
			)
			(stroke
				(width 0)
				(type default)
			)
			(fill no)
			(layer "F.Fab")
		)
		(pad "1" smd rect
			(at 0 -0.9652 270)
			(size 1.397 1.143)
			(layers "F.Cu" "F.Mask" "F.Paste")
			(net "SHELL_PLL_VDD")
		)
		(pad "2" smd rect
			(at 0 0.9652 270)
			(size 1.397 1.143)
			(layers "F.Cu" "F.Mask" "F.Paste")
			(net "GND")
		)
	)
	(footprint ""
		(layer "F.Cu")
		(at 100.11537 -116.84)
		(property "Reference" "TP263"
			(at 0 0 0)
			(layer "F.SilkS")
			(hide yes)
			(effects
				(font
					(size 1.27 1.27)
				)
			)
		)
		(property "Value" "TPAD28"
			(at 0.0127 -1.8034 0)
			(unlocked yes)
			(layer "F.Fab")
			(hide yes)
			(effects
				(font
					(size 1.016 1.016)
					(thickness 0.1524)
				)
			)
		)
		(property "Device Type" "TPAD28"
			(at 0.0127 -3.3274 0)
			(unlocked yes)
			(layer "F.Fab")
			(hide yes)
			(effects
				(font
					(size 1.016 1.016)
					(thickness 0.1524)
				)
			)
		)
		(duplicate_pad_numbers_are_jumpers no)
		(fp_poly
			(pts
				(arc
					(start 0.3556 0)
					(mid -0.3556 0)
					(end 0.3556 0)
				)
			)
			(stroke
				(width 0)
				(type default)
			)
			(fill no)
			(layer "F.CrtYd")
		)
		(fp_poly
			(pts
				(arc
					(start 0.6096 0)
					(mid -0.6096 0)
					(end 0.6096 0)
				)
			)
			(stroke
				(width 0)
				(type default)
			)
			(fill no)
			(layer "F.Fab")
		)
		(pad "1" smd circle
			(at 0 0)
			(size 0.7112 0.7112)
			(layers "F.Cu" "F.Mask" "F.Paste")
			(net "SIO_D_IN")
		)
	)
)
